# S9S_MB_2U (Grand Teton) — schematic netlist excerpt (pin names and nets, part order shuffled) for the footprints in the layout excerpt that follows; sources: Cadence DE-HDL packaged netlist, KiCad conversion of 03242023_DA0F0TMBIJ0_F0T_Motherboard_J_brd_V01_OCP.brd

J11  SCONN288_ADR50017P130CC  SCONN288_ADR50017-P130CC IO  pkg DDR288S_1-1VXB  page 92
  VIN_BULK0  = P12V_S3_AUX_CPU0_NVDIMM
  RFU0  = TP_CHF_CPU0_DIMM1_FRU_0
  VIN_MGMT  = P3V3_AUX
  HSCL  = I3C_SPD_DDREFGH_CPU0_LVC1_SCL_2
  HSDA  = I3C_SPD_DDREFGH_CPU0_LVC1_SDA
  VSS0  = GND
  DQ0_A  = M_F_CPU0_SA_DQ<0>
  VSS1  = GND
  DQ1_A  = M_F_CPU0_SA_DQ<1>
  VSS2  = GND
  DQS0_A_T  = M_F_CPU0_SA_DQS_DP<0>
  DQS0_A_C  = M_F_CPU0_SA_DQS_DN<0>
  VSS3  = GND
  DQ4_A  = M_F_CPU0_SA_DQ<4>
  VSS4  = GND
  DQ5_A  = M_F_CPU0_SA_DQ<5>
  VSS5  = GND
  DQ8_A  = M_F_CPU0_SA_DQ<8>
  VSS6  = GND
  DQ9_A  = M_F_CPU0_SA_DQ<9>
  VSS7  = GND
  DQS1_A_T  = M_F_CPU0_SA_DQS_DP<1>
  DQS1_A_C  = M_F_CPU0_SA_DQS_DN<1>
  VSS8  = GND
  DQ12_A  = M_F_CPU0_SA_DQ<12>
  VSS9  = GND
  DQ13_A  = M_F_CPU0_SA_DQ<13>
  VSS10  = GND
  DQ16_A  = M_F_CPU0_SA_DQ<16>
  VSS11  = GND
  DQ17_A  = M_F_CPU0_SA_DQ<17>
  VSS12  = GND
  DQS2_A_T  = M_F_CPU0_SA_DQS_DP<2>
  DQS2_A_C  = M_F_CPU0_SA_DQS_DN<2>
  VSS13  = GND
  DQ20_A  = M_F_CPU0_SA_DQ<20>
  VSS14  = GND
  DQ21_A  = M_F_CPU0_SA_DQ<21>
  VSS15  = GND
  DQ24_A  = M_F_CPU0_SA_DQ<24>
  VSS16  = GND
  DQ25_A  = M_F_CPU0_SA_DQ<25>
  VSS17  = GND
  DQS3_A_T  = M_F_CPU0_SA_DQS_DP<3>
  DQS3_A_C  = M_F_CPU0_SA_DQS_DN<3>
  VSS18  = GND
  DQ28_A  = M_F_CPU0_SA_DQ<28>
  VSS19  = GND
  DQ29_A  = M_F_CPU0_SA_DQ<29>
  VSS20  = GND
  CB0_A  = M_F_CPU0_SA_CB<0>
  VSS21  = GND
  CB1_A  = M_F_CPU0_SA_CB<1>
  VSS22  = GND
  DQS4_A_T  = M_F_CPU0_SA_DQS_DP<4>
  DQS4_A_C  = M_F_CPU0_SA_DQS_DN<4>
  VSS23  = GND
  CB4_A  = M_F_CPU0_SA_CB<4>
  VSS24  = GND
  CB5_A  = M_F_CPU0_SA_CB<5>
  VSS25  = GND
  ALERT_N  = M_F_CPU0_ALERT_N
  VSS26  = GND
  CS0_A_N  = M_F_CPU0_SA_CS_N<0>
  VSS27  = GND
  CA0_A  = M_F_CPU0_SA_CA<0>
  VSS28  = GND
  CA2_A  = M_F_CPU0_SA_CA<2>
  VSS29  = GND
  CA4_A  = M_F_CPU0_SA_CA<4>
  VSS30  = GND
  CA6_A  = M_F_CPU0_SA_CA<6>
  VSS31  = GND
  PAR_A  = M_F_CPU0_SA_PAR
  VSS32  = GND
  CA0_B  = M_F_CPU0_SB_CA<0>
  VSS33  = GND
  CA2_B  = M_F_CPU0_SB_CA<2>
  VSS34  = GND
  CA4_B  = M_F_CPU0_SB_CA<4>
  VSS35  = GND
  CA6_B  = M_F_CPU0_SB_CA<6>
  VSS36  = GND
  CS0_B_N  = M_F_CPU0_SB_CS_N<0>
  VSS37  = GND
  \lbd||rsp_a_n\  = M_F_CPU0_SA_RSP<0>
  \lbs||rsp_b_n\  = M_F_CPU0_SB_RSP<0>
  VSS38  = GND
  CB4_B  = M_F_CPU0_SB_CB<4>
  VSS39  = GND
  CB5_B  = M_F_CPU0_SB_CB<5>
  VSS40  = GND
  \dqs9_b_t||tdqs9_b_t||dbi4_b_n\  = M_F_CPU0_SB_DQS_DP<9>
  \dqs9_b_c||tdqs9_b_c\  = M_F_CPU0_SB_DQS_DN<9>
  VSS41  = GND
  CB0_B  = M_F_CPU0_SB_CB<0>
  VSS42  = GND
  CB1_B  = M_F_CPU0_SB_CB<1>
  VSS43  = GND
  DQ0_B  = M_F_CPU0_SB_DQ<0>
  VSS44  = GND
  DQ1_B  = M_F_CPU0_SB_DQ<1>
  VSS45  = GND
  DQS0_B_T  = M_F_CPU0_SB_DQS_DP<0>
  DQS0_B_C  = M_F_CPU0_SB_DQS_DN<0>
  VSS46  = GND
  DQ4_B  = M_F_CPU0_SB_DQ<4>
  VSS47  = GND
  DQ5_B  = M_F_CPU0_SB_DQ<5>
  VSS48  = GND
  DQ8_B  = M_F_CPU0_SB_DQ<8>
  VSS49  = GND
  DQ9_B  = M_F_CPU0_SB_DQ<9>
  VSS50  = GND
  DQS1_B_T  = M_F_CPU0_SB_DQS_DP<1>
  DQS1_B_C  = M_F_CPU0_SB_DQS_DN<1>
  VSS51  = GND
  DQ12_B  = M_F_CPU0_SB_DQ<12>
  VSS52  = GND
  DQ13_B  = M_F_CPU0_SB_DQ<13>
  VSS53  = GND
  DQ16_B  = M_F_CPU0_SB_DQ<16>
  VSS54  = GND
  DQ17_B  = M_F_CPU0_SB_DQ<17>
  VSS55  = GND
  DQS2_B_T  = M_F_CPU0_SB_DQS_DP<2>
  DQS2_B_C  = M_F_CPU0_SB_DQS_DN<2>
  VSS56  = GND
  DQ20_B  = M_F_CPU0_SB_DQ<20>
  VSS57  = GND
  DQ21_B  = M_F_CPU0_SB_DQ<21>
  VSS58  = GND
  DQ24_B  = M_F_CPU0_SB_DQ<24>
  VSS59  = GND
  DQ25_B  = M_F_CPU0_SB_DQ<25>
  VSS60  = GND
  DQS3_B_T  = M_F_CPU0_SB_DQS_DP<3>
  DQS3_B_C  = M_F_CPU0_SB_DQS_DN<3>
  VSS61  = GND
  DQ28_B  = M_F_CPU0_SB_DQ<28>
  VSS62  = GND
  DQ29_B  = M_F_CPU0_SB_DQ<29>
  VSS63  = GND
  RFU1  = TP_CHF_CPU0_DIMM1_FRU_1
  VIN_BULK1  = P12V_S3_AUX_CPU0_NVDIMM
  VIN_BULK2  = P12V_S3_AUX_CPU0_NVDIMM
  \pwr_good||fail_n\  = PWRGD_CHF_CPU0_DIMM1
  HSA  = PD_CHF_CPU0_DIMM1_SAA
  RFU2  = TP_CHF_CPU0_DIMM1_FRU_2
  RFU3  = TP_CHF_CPU0_DIMM1_FRU_3
  VSS64  = GND
  DQ2_A  = M_F_CPU0_SA_DQ<2>
  VSS65  = GND
  DQ3_A  = M_F_CPU0_SA_DQ<3>
  VSS66  = GND
  \dqs5_a_c||tdqs5_a_c||dqs5_a_t||tdqs5_a_t\  = M_F_CPU0_SA_DQS_DN<5>
  \dqs5_a_t||tdqs5_a_t\  = M_F_CPU0_SA_DQS_DP<5>
  VSS67  = GND
  DQ6_A  = M_F_CPU0_SA_DQ<6>
  VSS68  = GND
  DQ7_A  = M_F_CPU0_SA_DQ<7>
  VSS69  = GND
  DQ10_A  = M_F_CPU0_SA_DQ<10>
  VSS70  = GND
  DQ11_A  = M_F_CPU0_SA_DQ<11>
  VSS71  = GND
  \dqs6_a_c||tdqs6_a_c||dqs6_a_t||tdqs6_a_t\  = M_F_CPU0_SA_DQS_DN<6>
  \dqs6_a_t||tdqs6_a_t\  = M_F_CPU0_SA_DQS_DP<6>
  VSS72  = GND
  DQ14_A  = M_F_CPU0_SA_DQ<14>
  VSS73  = GND
  DQ15_A  = M_F_CPU0_SA_DQ<15>
  VSS74  = GND
  DQ18_A  = M_F_CPU0_SA_DQ<18>
  VSS75  = GND
  DQ19_A  = M_F_CPU0_SA_DQ<19>
  VSS76  = GND
  \dqs7_a_c||tdqs7_a_c\  = M_F_CPU0_SA_DQS_DN<7>
  \dqs7_a_t||tdqs7_a_t\  = M_F_CPU0_SA_DQS_DP<7>
  VSS77  = GND
  DQ22_A  = M_F_CPU0_SA_DQ<22>
  VSS78  = GND
  DQ23_A  = M_F_CPU0_SA_DQ<23>
  VSS79  = GND
  DQ26_A  = M_F_CPU0_SA_DQ<26>
  VSS80  = GND
  DQ27_A  = M_F_CPU0_SA_DQ<27>
  VSS81  = GND
  \dqs8_a_c||tdqs8_a_c\  = M_F_CPU0_SA_DQS_DN<8>
  \dqs8_a_t||tdqs8_a_t\  = M_F_CPU0_SA_DQS_DP<8>
  VSS82  = GND
  DQ30_A  = M_F_CPU0_SA_DQ<30>
  VSS83  = GND
  DQ31_A  = M_F_CPU0_SA_DQ<31>
  VSS84  = GND
  CB2_A  = M_F_CPU0_SA_CB<2>
  VSS85  = GND
  CB3_A  = M_F_CPU0_SA_CB<3>
  VSS86  = GND
  \dqs9_a_c||tdqs9_a_c\  = M_F_CPU0_SA_DQS_DN<9>
  \dqs9_a_t||tdqs9_a_t\  = M_F_CPU0_SA_DQS_DP<9>
  VSS87  = GND
  CB6_A  = M_F_CPU0_SA_CB<6>
  VSS88  = GND
  CB7_A  = M_F_CPU0_SA_CB<7>
  VSS89  = GND
  RESET_N  = RST_M_EF_CPU0_FPGA_N
  VSS90  = GND
  CS1_A_N  = M_F_CPU0_SA_CS_N<1>
  VSS91  = GND
  CA1_A  = M_F_CPU0_SA_CA<1>
  VSS92  = GND
  CA3_A  = M_F_CPU0_SA_CA<3>
  VSS93  = GND
  CA5_A  = M_F_CPU0_SA_CA<5>
  VSS94  = GND
  CK_T  = M_F_CPU0_CLK_DP<0>
  CK_C  = M_F_CPU0_CLK_DN<0>
  VSS95  = GND
  RFU4  = TP_CHF_CPU0_DIMM1_FRU_4
  CA1_B  = M_F_CPU0_SB_CA<1>
  VSS96  = GND
  CA3_B  = M_F_CPU0_SB_CA<3>
  VSS97  = GND
  CA5_B  = M_F_CPU0_SB_CA<5>
  VSS98  = GND
  PAR_B  = M_F_CPU0_SB_PAR
  VSS99  = GND
  CS1_B_N  = M_F_CPU0_SB_CS_N<1>
  VSS100  = GND
  RFU5  = TP_CHF_CPU0_DIMM1_FRU_5
  RFU6  = TP_CHF_CPU0_DIMM1_FRU_6
  VSS101  = GND
  CB6_B  = M_F_CPU0_SB_CB<6>
  VSS102  = GND
  CB7_B  = M_F_CPU0_SB_CB<7>
  VSS103  = GND
  DQS4_B_C  = M_F_CPU0_SB_DQS_DN<4>
  DQS4_B_T  = M_F_CPU0_SB_DQS_DP<4>
  VSS104  = GND
  CB2_B  = M_F_CPU0_SB_CB<2>
  VSS105  = GND
  CB3_B  = M_F_CPU0_SB_CB<3>
  VSS106  = GND
  DQ2_B  = M_F_CPU0_SB_DQ<2>
  VSS107  = GND
  DQ3_B  = M_F_CPU0_SB_DQ<3>
  VSS108  = GND
  \dqs5_b_c||tdqs5_b_c\  = M_F_CPU0_SB_DQS_DN<5>
  \dqs5_b_t||tdqs5_b_t\  = M_F_CPU0_SB_DQS_DP<5>
  VSS109  = GND
  DQ6_B  = M_F_CPU0_SB_DQ<6>
  VSS110  = GND
  DQ7_B  = M_F_CPU0_SB_DQ<7>
  VSS111  = GND
  DQ10_B  = M_F_CPU0_SB_DQ<10>
  VSS112  = GND
  DQ11_B  = M_F_CPU0_SB_DQ<11>
  VSS113  = GND
  \dqs6_b_c||tdqs6_b_c\  = M_F_CPU0_SB_DQS_DN<6>
  \dqs6_b_t||tdqs6_b_t\  = M_F_CPU0_SB_DQS_DP<6>
  VSS114  = GND
  DQ14_B  = M_F_CPU0_SB_DQ<14>
  VSS115  = GND
  DQ15_B  = M_F_CPU0_SB_DQ<15>
  VSS116  = GND
  DQ18_B  = M_F_CPU0_SB_DQ<18>
  VSS117  = GND
  DQ19_B  = M_F_CPU0_SB_DQ<19>
  VSS118  = GND
  \dqs7_b_c||tdqs7_b_c\  = M_F_CPU0_SB_DQS_DN<7>
  \dqs7_b_t||tdqs7_b_t\  = M_F_CPU0_SB_DQS_DP<7>
  VSS119  = GND
  DQ22_B  = M_F_CPU0_SB_DQ<22>
  VSS120  = GND
  DQ23_B  = M_F_CPU0_SB_DQ<23>
  VSS121  = GND
  DQ26_B  = M_F_CPU0_SB_DQ<26>
  VSS122  = GND
  DQ27_B  = M_F_CPU0_SB_DQ<27>
  VSS123  = GND
  \dqs8_b_c||tdqs8_b_c\  = M_F_CPU0_SB_DQS_DN<8>
  \dqs8_b_t||tdqs8_b_t\  = M_F_CPU0_SB_DQS_DP<8>
  VSS124  = GND
  DQ30_B  = M_F_CPU0_SB_DQ<30>
  VSS125  = GND
  DQ31_B  = M_F_CPU0_SB_DQ<31>
  VSS126  = GND
  G1  = GND
  G2  = GND
  G3  = GND

(kicad_pcb
	(version 20260206)
	(generator "pcbnew")
	(generator_version "10.0")
	(general
		(thickness 1.6)
		(legacy_teardrops no)
	)
	(paper "A4")
	(title_block
		(title "03242023_DA0F0TMBIJ0_F0T_Motherboard_J_brd_V01_OCP.brd")
		(comment 1 "Grand Teton / footprint 1952 of 6105 (J11), pads 1-45 of 291")
	)
	(layers
		(0 "F.Cu" signal "TOP")
		(4 "In1.Cu" signal "GND")
		(6 "In2.Cu" signal "IN1")
		(8 "In3.Cu" signal "GND1")
		(10 "In4.Cu" signal "IN2")
		(12 "In5.Cu" signal "GND2")
		(14 "In6.Cu" signal "IN3")
		(16 "In7.Cu" signal "GND3")
		(18 "In8.Cu" signal "VCC")
		(20 "In9.Cu" signal "VCC1")
		(22 "In10.Cu" signal "GND4")
		(24 "In11.Cu" signal "IN4")
		(26 "In12.Cu" signal "GND5")
		(28 "In13.Cu" signal "IN5")
		(30 "In14.Cu" signal "GND6")
		(32 "In15.Cu" signal "IN6")
		(34 "In16.Cu" signal "GND7")
		(2 "B.Cu" signal "BOTTOM")
		(9 "F.Adhes" user "F.Adhesive")
		(11 "B.Adhes" user "B.Adhesive")
		(13 "F.Paste" user "Package Geometry/Pastemask Top")
		(15 "B.Paste" user "Package Geometry/Pastemask Bottom")
		(5 "F.SilkS" user "Ref Des/Silkscreen Top")
		(7 "B.SilkS" user "Ref Des/Silkscreen Bottom")
		(1 "F.Mask" user "Board Geometry/Soldermask Top")
		(3 "B.Mask" user "Board Geometry/Soldermask Bottom")
		(17 "Dwgs.User" user "User.Drawings")
		(19 "Cmts.User" user "User.Comments")
		(21 "Eco1.User" user "User.Eco1")
		(23 "Eco2.User" user "User.Eco2")
		(25 "Edge.Cuts" user "Board Geometry/Outline")
		(27 "Margin" user)
		(31 "F.CrtYd" user "Package Geometry/Place Bound Top")
		(29 "B.CrtYd" user "Package Geometry/Place Bound Bottom")
		(35 "F.Fab" user "Ref Des/Assembly Top")
		(33 "B.Fab" user "Ref Des/Assembly Bottom")
	)
	(footprint ""
		(layer "F.Cu")
		(at 431.434748 -258.091686)
		(property "Reference" "J11"
			(at -3.683 -81.702148 0)
			(unlocked yes)
			(layer "F.SilkS")
			(effects
				(font
					(size 0.7874 0.5842)
					(thickness 0.1524)
				)
				(justify left)
			)
		)
		(property "Value" ""
			(at 0 0 0)
			(layer "F.Fab")
			(effects
				(font
					(size 1.27 1.27)
				)
			)
		)
		(duplicate_pad_numbers_are_jumpers no)
		(pad "1" smd rect
			(at -2.050034 -63.324994 270)
			(size 0.519938 1.4986)
			(layers "F.Cu" "F.Mask" "F.Paste")
			(net "P12V_S3_AUX_CPU0_NVDIMM")
		)
		(pad "2" smd rect
			(at -2.050034 -62.47511 270)
			(size 0.519938 1.4986)
			(layers "F.Cu" "F.Mask" "F.Paste")
			(net "TP_CHF_CPU0_DIMM1_FRU_0")
		)
		(pad "3" smd rect
			(at -2.050034 -61.624972 270)
			(size 0.519938 1.4986)
			(layers "F.Cu" "F.Mask" "F.Paste")
			(net "P3V3_AUX")
		)
		(pad "4" smd rect
			(at -2.050034 -60.775088 270)
			(size 0.519938 1.4986)
			(layers "F.Cu" "F.Mask" "F.Paste")
			(net "I3C_SPD_DDREFGH_CPU0_LVC1_SCL_2")
		)
		(pad "5" smd rect
			(at -2.050034 -59.92495 270)
			(size 0.519938 1.4986)
			(layers "F.Cu" "F.Mask" "F.Paste")
			(net "I3C_SPD_DDREFGH_CPU0_LVC1_SDA")
		)
		(pad "6" smd rect
			(at -2.050034 -59.075066 270)
			(size 0.519938 1.4986)
			(layers "F.Cu" "F.Mask" "F.Paste")
			(net "GND")
		)
		(pad "7" smd rect
			(at -2.050034 -58.224928 270)
			(size 0.519938 1.4986)
			(layers "F.Cu" "F.Mask" "F.Paste")
			(net "M_F_CPU0_SA_DQ<0>")
		)
		(pad "8" smd rect
			(at -2.050034 -57.375044 270)
			(size 0.519938 1.4986)
			(layers "F.Cu" "F.Mask" "F.Paste")
			(net "GND")
		)
		(pad "9" smd rect
			(at -2.050034 -56.524906 270)
			(size 0.519938 1.4986)
			(layers "F.Cu" "F.Mask" "F.Paste")
			(net "M_F_CPU0_SA_DQ<1>")
		)
		(pad "10" smd rect
			(at -2.050034 -55.675022 270)
			(size 0.519938 1.4986)
			(layers "F.Cu" "F.Mask" "F.Paste")
			(net "GND")
		)
		(pad "11" smd rect
			(at -2.050034 -54.824884 270)
			(size 0.519938 1.4986)
			(layers "F.Cu" "F.Mask" "F.Paste")
			(net "M_F_CPU0_SA_DQS_DP<0>")
		)
		(pad "12" smd rect
			(at -2.050034 -53.975 270)
			(size 0.519938 1.4986)
			(layers "F.Cu" "F.Mask" "F.Paste")
			(net "M_F_CPU0_SA_DQS_DN<0>")
		)
		(pad "13" smd rect
			(at -2.050034 -53.125116 270)
			(size 0.519938 1.4986)
			(layers "F.Cu" "F.Mask" "F.Paste")
			(net "GND")
		)
		(pad "14" smd rect
			(at -2.050034 -52.274978 270)
			(size 0.519938 1.4986)
			(layers "F.Cu" "F.Mask" "F.Paste")
			(net "M_F_CPU0_SA_DQ<4>")
		)
		(pad "15" smd rect
			(at -2.050034 -51.425094 270)
			(size 0.519938 1.4986)
			(layers "F.Cu" "F.Mask" "F.Paste")
			(net "GND")
		)
		(pad "16" smd rect
			(at -2.050034 -50.574956 270)
			(size 0.519938 1.4986)
			(layers "F.Cu" "F.Mask" "F.Paste")
			(net "M_F_CPU0_SA_DQ<5>")
		)
		(pad "17" smd rect
			(at -2.050034 -49.725072 270)
			(size 0.519938 1.4986)
			(layers "F.Cu" "F.Mask" "F.Paste")
			(net "GND")
		)
		(pad "18" smd rect
			(at -2.050034 -48.874934 270)
			(size 0.519938 1.4986)
			(layers "F.Cu" "F.Mask" "F.Paste")
			(net "M_F_CPU0_SA_DQ<8>")
		)
		(pad "19" smd rect
			(at -2.050034 -48.02505 270)
			(size 0.519938 1.4986)
			(layers "F.Cu" "F.Mask" "F.Paste")
			(net "GND")
		)
		(pad "20" smd rect
			(at -2.050034 -47.174912 270)
			(size 0.519938 1.4986)
			(layers "F.Cu" "F.Mask" "F.Paste")
			(net "M_F_CPU0_SA_DQ<9>")
		)
		(pad "21" smd rect
			(at -2.050034 -46.325028 270)
			(size 0.519938 1.4986)
			(layers "F.Cu" "F.Mask" "F.Paste")
			(net "GND")
		)
		(pad "22" smd rect
			(at -2.050034 -45.47489 270)
			(size 0.519938 1.4986)
			(layers "F.Cu" "F.Mask" "F.Paste")
			(net "M_F_CPU0_SA_DQS_DP<1>")
		)
		(pad "23" smd rect
			(at -2.050034 -44.625006 270)
			(size 0.519938 1.4986)
			(layers "F.Cu" "F.Mask" "F.Paste")
			(net "M_F_CPU0_SA_DQS_DN<1>")
		)
		(pad "24" smd rect
			(at -2.050034 -43.775122 270)
			(size 0.519938 1.4986)
			(layers "F.Cu" "F.Mask" "F.Paste")
			(net "GND")
		)
		(pad "25" smd rect
			(at -2.050034 -42.924984 270)
			(size 0.519938 1.4986)
			(layers "F.Cu" "F.Mask" "F.Paste")
			(net "M_F_CPU0_SA_DQ<12>")
		)
		(pad "26" smd rect
			(at -2.050034 -42.0751 270)
			(size 0.519938 1.4986)
			(layers "F.Cu" "F.Mask" "F.Paste")
			(net "GND")
		)
		(pad "27" smd rect
			(at -2.050034 -41.224962 270)
			(size 0.519938 1.4986)
			(layers "F.Cu" "F.Mask" "F.Paste")
			(net "M_F_CPU0_SA_DQ<13>")
		)
		(pad "28" smd rect
			(at -2.050034 -40.375078 270)
			(size 0.519938 1.4986)
			(layers "F.Cu" "F.Mask" "F.Paste")
			(net "GND")
		)
		(pad "29" smd rect
			(at -2.050034 -39.52494 270)
			(size 0.519938 1.4986)
			(layers "F.Cu" "F.Mask" "F.Paste")
			(net "M_F_CPU0_SA_DQ<16>")
		)
		(pad "30" smd rect
			(at -2.050034 -38.675056 270)
			(size 0.519938 1.4986)
			(layers "F.Cu" "F.Mask" "F.Paste")
			(net "GND")
		)
		(pad "31" smd rect
			(at -2.050034 -37.824918 270)
			(size 0.519938 1.4986)
			(layers "F.Cu" "F.Mask" "F.Paste")
			(net "M_F_CPU0_SA_DQ<17>")
		)
		(pad "32" smd rect
			(at -2.050034 -36.975034 270)
			(size 0.519938 1.4986)
			(layers "F.Cu" "F.Mask" "F.Paste")
			(net "GND")
		)
		(pad "33" smd rect
			(at -2.050034 -36.124896 270)
			(size 0.519938 1.4986)
			(layers "F.Cu" "F.Mask" "F.Paste")
			(net "M_F_CPU0_SA_DQS_DP<2>")
		)
		(pad "34" smd rect
			(at -2.050034 -35.275012 270)
			(size 0.519938 1.4986)
			(layers "F.Cu" "F.Mask" "F.Paste")
			(net "M_F_CPU0_SA_DQS_DN<2>")
		)
		(pad "35" smd rect
			(at -2.050034 -34.425128 270)
			(size 0.519938 1.4986)
			(layers "F.Cu" "F.Mask" "F.Paste")
			(net "GND")
		)
		(pad "36" smd rect
			(at -2.050034 -33.57499 270)
			(size 0.519938 1.4986)
			(layers "F.Cu" "F.Mask" "F.Paste")
			(net "M_F_CPU0_SA_DQ<20>")
		)
		(pad "37" smd rect
			(at -2.050034 -32.725106 270)
			(size 0.519938 1.4986)
			(layers "F.Cu" "F.Mask" "F.Paste")
			(net "GND")
		)
		(pad "38" smd rect
			(at -2.050034 -31.874968 270)
			(size 0.519938 1.4986)
			(layers "F.Cu" "F.Mask" "F.Paste")
			(net "M_F_CPU0_SA_DQ<21>")
		)
		(pad "39" smd rect
			(at -2.050034 -31.025084 270)
			(size 0.519938 1.4986)
			(layers "F.Cu" "F.Mask" "F.Paste")
			(net "GND")
		)
		(pad "40" smd rect
			(at -2.050034 -30.174946 270)
			(size 0.519938 1.4986)
			(layers "F.Cu" "F.Mask" "F.Paste")
			(net "M_F_CPU0_SA_DQ<24>")
		)
		(pad "41" smd rect
			(at -2.050034 -29.325062 270)
			(size 0.519938 1.4986)
			(layers "F.Cu" "F.Mask" "F.Paste")
			(net "GND")
		)
		(pad "42" smd rect
			(at -2.050034 -28.474924 270)
			(size 0.519938 1.4986)
			(layers "F.Cu" "F.Mask" "F.Paste")
			(net "M_F_CPU0_SA_DQ<25>")
		)
		(pad "43" smd rect
			(at -2.050034 -27.62504 270)
			(size 0.519938 1.4986)
			(layers "F.Cu" "F.Mask" "F.Paste")
			(net "GND")
		)
		(pad "44" smd rect
			(at -2.050034 -26.774902 270)
			(size 0.519938 1.4986)
			(layers "F.Cu" "F.Mask" "F.Paste")
			(net "M_F_CPU0_SA_DQS_DP<3>")
		)
		(pad "45" smd rect
			(at -2.050034 -25.925018 270)
			(size 0.519938 1.4986)
			(layers "F.Cu" "F.Mask" "F.Paste")
			(net "M_F_CPU0_SA_DQS_DN<3>")
		)
	)
)
